(kicad_pcb
	(version 20260206)
	(generator "pcbnew")
	(generator_version "10.0")
	(general
		(thickness 1.6)
		(legacy_teardrops no)
	)
	(paper "A4")
	(title_block
		(title "04192023_DAF0TMB3IC0_F0TG_MB_C_brd_V02_OCP.brd")
		(comment 1 "Grand Teton / footprints 852-858 of 8354")
	)
	(layers
		(0 "F.Cu" signal "TOP")
		(4 "In1.Cu" signal "GND")
		(6 "In2.Cu" signal "IN1")
		(8 "In3.Cu" signal "GND1")
		(10 "In4.Cu" signal "IN2")
		(12 "In5.Cu" signal "GND2")
		(14 "In6.Cu" signal "IN3")
		(16 "In7.Cu" signal "GND3")
		(18 "In8.Cu" signal "VCC")
		(20 "In9.Cu" signal "VCC1")
		(22 "In10.Cu" signal "GND4")
		(24 "In11.Cu" signal "IN4")
		(26 "In12.Cu" signal "GND5")
		(28 "In13.Cu" signal "IN5")
		(30 "In14.Cu" signal "GND6")
		(32 "In15.Cu" signal "IN6")
		(34 "In16.Cu" signal "GND7")
		(2 "B.Cu" signal "BOTTOM")
		(9 "F.Adhes" user "F.Adhesive")
		(11 "B.Adhes" user "B.Adhesive")
		(13 "F.Paste" user "Package Geometry/Pastemask Top")
		(15 "B.Paste" user "Package Geometry/Pastemask Bottom")
		(5 "F.SilkS" user "Ref Des/Silkscreen Top")
		(7 "B.SilkS" user "Ref Des/Silkscreen Bottom")
		(1 "F.Mask" user "Board Geometry/Soldermask Top")
		(3 "B.Mask" user "Board Geometry/Soldermask Bottom")
		(17 "Dwgs.User" user "User.Drawings")
		(19 "Cmts.User" user "User.Comments")
		(21 "Eco1.User" user "User.Eco1")
		(23 "Eco2.User" user "User.Eco2")
		(25 "Edge.Cuts" user "Board Geometry/Outline")
		(27 "Margin" user)
		(31 "F.CrtYd" user "Package Geometry/Place Bound Top")
		(29 "B.CrtYd" user "Package Geometry/Place Bound Bottom")
		(35 "F.Fab" user "Ref Des/Assembly Top")
		(33 "B.Fab" user "Ref Des/Assembly Bottom")
	)
	(footprint ""
		(layer "F.Cu")
		(at 257.86588 -50.545746)
		(property "Reference" "PC2196"
			(at 0 0 0)
			(layer "F.SilkS")
			(hide yes)
			(effects
				(font
					(size 1.27 1.27)
				)
			)
		)
		(property "Value" ""
			(at 0 0 0)
			(layer "F.Fab")
			(effects
				(font
					(size 1.27 1.27)
				)
			)
		)
		(duplicate_pad_numbers_are_jumpers no)
		(fp_line
			(start -0.7874 -0.4064)
			(end 0.7874 -0.4064)
			(stroke
				(width 0.1524)
				(type default)
			)
			(layer "F.SilkS")
		)
		(fp_line
			(start -0.7874 0.4064)
			(end -0.7874 -0.4064)
			(stroke
				(width 0.1524)
				(type default)
			)
			(layer "F.SilkS")
		)
		(fp_line
			(start 0.7874 -0.4064)
			(end 0.7874 0.4064)
			(stroke
				(width 0.1524)
				(type default)
			)
			(layer "F.SilkS")
		)
		(fp_line
			(start 0.7874 0.4064)
			(end -0.7874 0.4064)
			(stroke
				(width 0.1524)
				(type default)
			)
			(layer "F.SilkS")
		)
		(fp_line
			(start -0.67945 -0.305054)
			(end -0.12065 -0.305054)
			(stroke
				(width 0.1)
				(type default)
			)
			(layer "F.Fab")
		)
		(fp_line
			(start -0.67945 0.3048)
			(end -0.67945 -0.305054)
			(stroke
				(width 0.1)
				(type default)
			)
			(layer "F.Fab")
		)
		(fp_line
			(start -0.12065 -0.305054)
			(end -0.12065 -0.2794)
			(stroke
				(width 0.1)
				(type default)
			)
			(layer "F.Fab")
		)
		(fp_line
			(start -0.12065 -0.2794)
			(end 0.12065 -0.2794)
			(stroke
				(width 0.1)
				(type default)
			)
			(layer "F.Fab")
		)
		(fp_line
			(start -0.12065 0.2794)
			(end -0.12065 0.3048)
			(stroke
				(width 0.1)
				(type default)
			)
			(layer "F.Fab")
		)
		(fp_line
			(start -0.12065 0.3048)
			(end -0.67945 0.3048)
			(stroke
				(width 0.1)
				(type default)
			)
			(layer "F.Fab")
		)
		(fp_line
			(start 0.120396 0.2794)
			(end -0.12065 0.2794)
			(stroke
				(width 0.1)
				(type default)
			)
			(layer "F.Fab")
		)
		(fp_line
			(start 0.120396 0.3048)
			(end 0.120396 0.2794)
			(stroke
				(width 0.1)
				(type default)
			)
			(layer "F.Fab")
		)
		(fp_line
			(start 0.12065 -0.3048)
			(end 0.67945 -0.3048)
			(stroke
				(width 0.1)
				(type default)
			)
			(layer "F.Fab")
		)
		(fp_line
			(start 0.12065 -0.2794)
			(end 0.12065 -0.3048)
			(stroke
				(width 0.1)
				(type default)
			)
			(layer "F.Fab")
		)
		(fp_line
			(start 0.67945 -0.3048)
			(end 0.67945 0.3048)
			(stroke
				(width 0.1)
				(type default)
			)
			(layer "F.Fab")
		)
		(fp_line
			(start 0.67945 0.3048)
			(end 0.120396 0.3048)
			(stroke
				(width 0.1)
				(type default)
			)
			(layer "F.Fab")
		)
		(pad "1" smd circle
			(at -0.40005 0)
			(size 0 0)
			(layers "F.Cu" "F.Mask" "F.Paste")
			(net "P12V_E1S_TIMER_0")
		)
		(pad "2" smd circle
			(at 0.40005 0)
			(size 0 0)
			(layers "F.Cu" "F.Mask" "F.Paste")
			(net "GND")
		)
	)
	(footprint ""
		(layer "F.Cu")
		(at 362.025438 -409.947364)
		(property "Reference" "R9014"
			(at 0 0 0)
			(layer "F.SilkS")
			(hide yes)
			(effects
				(font
					(size 1.27 1.27)
				)
			)
		)
		(property "Value" ""
			(at 0 0 0)
			(layer "F.Fab")
			(effects
				(font
					(size 1.27 1.27)
				)
			)
		)
		(duplicate_pad_numbers_are_jumpers no)
		(fp_line
			(start -0.7874 -0.4064)
			(end 0.7874 -0.4064)
			(stroke
				(width 0.1524)
				(type default)
			)
			(layer "F.SilkS")
		)
		(fp_line
			(start -0.7874 0.4064)
			(end -0.7874 -0.4064)
			(stroke
				(width 0.1524)
				(type default)
			)
			(layer "F.SilkS")
		)
		(fp_line
			(start 0.7874 -0.4064)
			(end 0.7874 0.4064)
			(stroke
				(width 0.1524)
				(type default)
			)
			(layer "F.SilkS")
		)
		(fp_line
			(start 0.7874 0.4064)
			(end -0.7874 0.4064)
			(stroke
				(width 0.1524)
				(type default)
			)
			(layer "F.SilkS")
		)
		(fp_line
			(start -0.67945 -0.305054)
			(end -0.12065 -0.305054)
			(stroke
				(width 0.1)
				(type default)
			)
			(layer "F.Fab")
		)
		(fp_line
			(start -0.67945 0.3048)
			(end -0.67945 -0.305054)
			(stroke
				(width 0.1)
				(type default)
			)
			(layer "F.Fab")
		)
		(fp_line
			(start -0.12065 -0.305054)
			(end -0.12065 -0.2794)
			(stroke
				(width 0.1)
				(type default)
			)
			(layer "F.Fab")
		)
		(fp_line
			(start -0.12065 -0.2794)
			(end 0.12065 -0.2794)
			(stroke
				(width 0.1)
				(type default)
			)
			(layer "F.Fab")
		)
		(fp_line
			(start -0.12065 0.2794)
			(end -0.12065 0.3048)
			(stroke
				(width 0.1)
				(type default)
			)
			(layer "F.Fab")
		)
		(fp_line
			(start -0.12065 0.3048)
			(end -0.67945 0.3048)
			(stroke
				(width 0.1)
				(type default)
			)
			(layer "F.Fab")
		)
		(fp_line
			(start 0.120396 0.2794)
			(end -0.12065 0.2794)
			(stroke
				(width 0.1)
				(type default)
			)
			(layer "F.Fab")
		)
		(fp_line
			(start 0.120396 0.3048)
			(end 0.120396 0.2794)
			(stroke
				(width 0.1)
				(type default)
			)
			(layer "F.Fab")
		)
		(fp_line
			(start 0.12065 -0.3048)
			(end 0.67945 -0.3048)
			(stroke
				(width 0.1)
				(type default)
			)
			(layer "F.Fab")
		)
		(fp_line
			(start 0.12065 -0.2794)
			(end 0.12065 -0.3048)
			(stroke
				(width 0.1)
				(type default)
			)
			(layer "F.Fab")
		)
		(fp_line
			(start 0.67945 -0.3048)
			(end 0.67945 0.3048)
			(stroke
				(width 0.1)
				(type default)
			)
			(layer "F.Fab")
		)
		(fp_line
			(start 0.67945 0.3048)
			(end 0.120396 0.3048)
			(stroke
				(width 0.1)
				(type default)
			)
			(layer "F.Fab")
		)
		(pad "1" smd circle
			(at -0.40005 0)
			(size 0 0)
			(layers "F.Cu" "F.Mask" "F.Paste")
			(net "P3V3_AUX")
		)
		(pad "2" smd circle
			(at 0.40005 0)
			(size 0 0)
			(layers "F.Cu" "F.Mask" "F.Paste")
			(net "PRSNT_CABLE_GPU_A3_N")
		)
	)
	(footprint ""
		(layer "F.Cu")
		(at 392.840972 -384.449828)
		(property "Reference" "C872"
			(at 0 0 0)
			(layer "F.SilkS")
			(hide yes)
			(effects
				(font
					(size 1.27 1.27)
				)
			)
		)
		(property "Value" ""
			(at 0 0 0)
			(layer "F.Fab")
			(effects
				(font
					(size 1.27 1.27)
				)
			)
		)
		(duplicate_pad_numbers_are_jumpers no)
		(fp_line
			(start -0.299974 -0.150114)
			(end 0.299974 -0.150114)
			(stroke
				(width 0.1)
				(type default)
			)
			(layer "F.Fab")
		)
		(fp_line
			(start -0.299974 0.150114)
			(end -0.299974 -0.150114)
			(stroke
				(width 0.1)
				(type default)
			)
			(layer "F.Fab")
		)
		(fp_line
			(start 0.299974 -0.150114)
			(end 0.299974 0.150114)
			(stroke
				(width 0.1)
				(type default)
			)
			(layer "F.Fab")
		)
		(fp_line
			(start 0.299974 0.150114)
			(end -0.299974 0.150114)
			(stroke
				(width 0.1)
				(type default)
			)
			(layer "F.Fab")
		)
		(pad "1" smd rect
			(at -0.2667 0)
			(size 0.3048 0.381)
			(layers "F.Cu" "F.Mask" "F.Paste")
			(net "P5E_CPU0_P3_TX_C_DN<14>")
		)
		(pad "2" smd rect
			(at 0.2667 0)
			(size 0.3048 0.381)
			(layers "F.Cu" "F.Mask" "F.Paste")
			(net "P5E_CPU0_P3_TX_DN<14>")
		)
	)
	(footprint ""
		(layer "F.Cu")
		(at 19.241516 -41.958514)
		(property "Reference" "R1322"
			(at 0 0 0)
			(layer "F.SilkS")
			(hide yes)
			(effects
				(font
					(size 1.27 1.27)
				)
			)
		)
		(property "Value" ""
			(at 0 0 0)
			(layer "F.Fab")
			(effects
				(font
					(size 1.27 1.27)
				)
			)
		)
		(duplicate_pad_numbers_are_jumpers no)
		(fp_line
			(start -0.7874 -0.4064)
			(end 0.7874 -0.4064)
			(stroke
				(width 0.1524)
				(type default)
			)
			(layer "F.SilkS")
		)
		(fp_line
			(start -0.7874 0.4064)
			(end -0.7874 -0.4064)
			(stroke
				(width 0.1524)
				(type default)
			)
			(layer "F.SilkS")
		)
		(fp_line
			(start 0.7874 -0.4064)
			(end 0.7874 0.4064)
			(stroke
				(width 0.1524)
				(type default)
			)
			(layer "F.SilkS")
		)
		(fp_line
			(start 0.7874 0.4064)
			(end -0.7874 0.4064)
			(stroke
				(width 0.1524)
				(type default)
			)
			(layer "F.SilkS")
		)
		(fp_line
			(start -0.67945 -0.305054)
			(end -0.12065 -0.305054)
			(stroke
				(width 0.1)
				(type default)
			)
			(layer "F.Fab")
		)
		(fp_line
			(start -0.67945 0.3048)
			(end -0.67945 -0.305054)
			(stroke
				(width 0.1)
				(type default)
			)
			(layer "F.Fab")
		)
		(fp_line
			(start -0.12065 -0.305054)
			(end -0.12065 -0.2794)
			(stroke
				(width 0.1)
				(type default)
			)
			(layer "F.Fab")
		)
		(fp_line
			(start -0.12065 -0.2794)
			(end 0.12065 -0.2794)
			(stroke
				(width 0.1)
				(type default)
			)
			(layer "F.Fab")
		)
		(fp_line
			(start -0.12065 0.2794)
			(end -0.12065 0.3048)
			(stroke
				(width 0.1)
				(type default)
			)
			(layer "F.Fab")
		)
		(fp_line
			(start -0.12065 0.3048)
			(end -0.67945 0.3048)
			(stroke
				(width 0.1)
				(type default)
			)
			(layer "F.Fab")
		)
		(fp_line
			(start 0.120396 0.2794)
			(end -0.12065 0.2794)
			(stroke
				(width 0.1)
				(type default)
			)
			(layer "F.Fab")
		)
		(fp_line
			(start 0.120396 0.3048)
			(end 0.120396 0.2794)
			(stroke
				(width 0.1)
				(type default)
			)
			(layer "F.Fab")
		)
		(fp_line
			(start 0.12065 -0.3048)
			(end 0.67945 -0.3048)
			(stroke
				(width 0.1)
				(type default)
			)
			(layer "F.Fab")
		)
		(fp_line
			(start 0.12065 -0.2794)
			(end 0.12065 -0.3048)
			(stroke
				(width 0.1)
				(type default)
			)
			(layer "F.Fab")
		)
		(fp_line
			(start 0.67945 -0.3048)
			(end 0.67945 0.3048)
			(stroke
				(width 0.1)
				(type default)
			)
			(layer "F.Fab")
		)
		(fp_line
			(start 0.67945 0.3048)
			(end 0.120396 0.3048)
			(stroke
				(width 0.1)
				(type default)
			)
			(layer "F.Fab")
		)
		(pad "1" smd circle
			(at -0.40005 0)
			(size 0 0)
			(layers "F.Cu" "F.Mask" "F.Paste")
			(net "P3V3_AUX")
		)
		(pad "2" smd circle
			(at 0.40005 0)
			(size 0 0)
			(layers "F.Cu" "F.Mask" "F.Paste")
			(net "INA230_7_A1")
		)
	)
	(footprint ""
		(layer "F.Cu")
		(at 117.895624 -257.455416 180)
		(property "Reference" "C2422"
			(at 0 0 180)
			(layer "F.SilkS")
			(hide yes)
			(effects
				(font
					(size 1.27 1.27)
				)
			)
		)
		(property "Value" ""
			(at 0 0 180)
			(layer "F.Fab")
			(effects
				(font
					(size 1.27 1.27)
				)
			)
		)
		(duplicate_pad_numbers_are_jumpers no)
		(fp_line
			(start 0.7874 0.4064)
			(end -0.7874 0.4064)
			(stroke
				(width 0.1524)
				(type default)
			)
			(layer "F.SilkS")
		)
		(fp_line
			(start 0.7874 -0.4064)
			(end 0.7874 0.4064)
			(stroke
				(width 0.1524)
				(type default)
			)
			(layer "F.SilkS")
		)
		(fp_line
			(start -0.7874 0.4064)
			(end -0.7874 -0.4064)
			(stroke
				(width 0.1524)
				(type default)
			)
			(layer "F.SilkS")
		)
		(fp_line
			(start -0.7874 -0.4064)
			(end 0.7874 -0.4064)
			(stroke
				(width 0.1524)
				(type default)
			)
			(layer "F.SilkS")
		)
		(fp_line
			(start 0.67945 0.3048)
			(end 0.120396 0.3048)
			(stroke
				(width 0.1)
				(type default)
			)
			(layer "F.Fab")
		)
		(fp_line
			(start 0.67945 -0.3048)
			(end 0.67945 0.3048)
			(stroke
				(width 0.1)
				(type default)
			)
			(layer "F.Fab")
		)
		(fp_line
			(start 0.12065 -0.2794)
			(end 0.12065 -0.3048)
			(stroke
				(width 0.1)
				(type default)
			)
			(layer "F.Fab")
		)
		(fp_line
			(start 0.12065 -0.3048)
			(end 0.67945 -0.3048)
			(stroke
				(width 0.1)
				(type default)
			)
			(layer "F.Fab")
		)
		(fp_line
			(start 0.120396 0.3048)
			(end 0.120396 0.2794)
			(stroke
				(width 0.1)
				(type default)
			)
			(layer "F.Fab")
		)
		(fp_line
			(start 0.120396 0.2794)
			(end -0.12065 0.2794)
			(stroke
				(width 0.1)
				(type default)
			)
			(layer "F.Fab")
		)
		(fp_line
			(start -0.12065 0.3048)
			(end -0.67945 0.3048)
			(stroke
				(width 0.1)
				(type default)
			)
			(layer "F.Fab")
		)
		(fp_line
			(start -0.12065 0.2794)
			(end -0.12065 0.3048)
			(stroke
				(width 0.1)
				(type default)
			)
			(layer "F.Fab")
		)
		(fp_line
			(start -0.12065 -0.2794)
			(end 0.12065 -0.2794)
			(stroke
				(width 0.1)
				(type default)
			)
			(layer "F.Fab")
		)
		(fp_line
			(start -0.12065 -0.305054)
			(end -0.12065 -0.2794)
			(stroke
				(width 0.1)
				(type default)
			)
			(layer "F.Fab")
		)
		(fp_line
			(start -0.67945 0.3048)
			(end -0.67945 -0.305054)
			(stroke
				(width 0.1)
				(type default)
			)
			(layer "F.Fab")
		)
		(fp_line
			(start -0.67945 -0.305054)
			(end -0.12065 -0.305054)
			(stroke
				(width 0.1)
				(type default)
			)
			(layer "F.Fab")
		)
		(pad "1" smd circle
			(at -0.40005 0 180)
			(size 0 0)
			(layers "F.Cu" "F.Mask" "F.Paste")
			(net "PVDDCR_SOC_P1")
		)
		(pad "2" smd circle
			(at 0.40005 0 180)
			(size 0 0)
			(layers "F.Cu" "F.Mask" "F.Paste")
			(net "GND")
		)
	)
	(footprint ""
		(layer "F.Cu")
		(at 165.8112 -429.9712 90)
		(property "Reference" "R2705"
			(at 0 0 90)
			(layer "F.SilkS")
			(hide yes)
			(effects
				(font
					(size 1.27 1.27)
				)
			)
		)
		(property "Value" ""
			(at 0 0 90)
			(layer "F.Fab")
			(effects
				(font
					(size 1.27 1.27)
				)
			)
		)
		(duplicate_pad_numbers_are_jumpers no)
		(fp_line
			(start 0.7874 -0.4064)
			(end 0.7874 0.4064)
			(stroke
				(width 0.1524)
				(type default)
			)
			(layer "F.SilkS")
		)
		(fp_line
			(start -0.7874 -0.4064)
			(end 0.7874 -0.4064)
			(stroke
				(width 0.1524)
				(type default)
			)
			(layer "F.SilkS")
		)
		(fp_line
			(start 0.7874 0.4064)
			(end -0.7874 0.4064)
			(stroke
				(width 0.1524)
				(type default)
			)
			(layer "F.SilkS")
		)
		(fp_line
			(start -0.7874 0.4064)
			(end -0.7874 -0.4064)
			(stroke
				(width 0.1524)
				(type default)
			)
			(layer "F.SilkS")
		)
		(fp_line
			(start -0.12065 -0.305054)
			(end -0.12065 -0.2794)
			(stroke
				(width 0.1)
				(type default)
			)
			(layer "F.Fab")
		)
		(fp_line
			(start -0.67945 -0.305054)
			(end -0.12065 -0.305054)
			(stroke
				(width 0.1)
				(type default)
			)
			(layer "F.Fab")
		)
		(fp_line
			(start 0.67945 -0.3048)
			(end 0.67945 0.3048)
			(stroke
				(width 0.1)
				(type default)
			)
			(layer "F.Fab")
		)
		(fp_line
			(start 0.12065 -0.3048)
			(end 0.67945 -0.3048)
			(stroke
				(width 0.1)
				(type default)
			)
			(layer "F.Fab")
		)
		(fp_line
			(start 0.12065 -0.2794)
			(end 0.12065 -0.3048)
			(stroke
				(width 0.1)
				(type default)
			)
			(layer "F.Fab")
		)
		(fp_line
			(start -0.12065 -0.2794)
			(end 0.12065 -0.2794)
			(stroke
				(width 0.1)
				(type default)
			)
			(layer "F.Fab")
		)
		(fp_line
			(start 0.120396 0.2794)
			(end -0.12065 0.2794)
			(stroke
				(width 0.1)
				(type default)
			)
			(layer "F.Fab")
		)
		(fp_line
			(start -0.12065 0.2794)
			(end -0.12065 0.3048)
			(stroke
				(width 0.1)
				(type default)
			)
			(layer "F.Fab")
		)
		(fp_line
			(start 0.67945 0.3048)
			(end 0.120396 0.3048)
			(stroke
				(width 0.1)
				(type default)
			)
			(layer "F.Fab")
		)
		(fp_line
			(start 0.120396 0.3048)
			(end 0.120396 0.2794)
			(stroke
				(width 0.1)
				(type default)
			)
			(layer "F.Fab")
		)
		(fp_line
			(start -0.12065 0.3048)
			(end -0.67945 0.3048)
			(stroke
				(width 0.1)
				(type default)
			)
			(layer "F.Fab")
		)
		(fp_line
			(start -0.67945 0.3048)
			(end -0.67945 -0.305054)
			(stroke
				(width 0.1)
				(type default)
			)
			(layer "F.Fab")
		)
		(pad "1" smd circle
			(at -0.40005 0 90)
			(size 0 0)
			(layers "F.Cu" "F.Mask" "F.Paste")
			(net "SMB_BMC_SWB_R_SCL")
		)
		(pad "2" smd circle
			(at 0.40005 0 90)
			(size 0 0)
			(layers "F.Cu" "F.Mask" "F.Paste")
			(net "SMB_BMC_SWB_BUF_R_SCL")
		)
	)
	(footprint ""
		(layer "F.Cu")
		(at 294.421052 -119.301514)
		(property "Reference" "R3580"
			(at 0 0 0)
			(layer "F.SilkS")
			(hide yes)
			(effects
				(font
					(size 1.27 1.27)
				)
			)
		)
		(property "Value" ""
			(at 0 0 0)
			(layer "F.Fab")
			(effects
				(font
					(size 1.27 1.27)
				)
			)
		)
		(duplicate_pad_numbers_are_jumpers no)
		(fp_line
			(start -0.7874 -0.4064)
			(end 0.7874 -0.4064)
			(stroke
				(width 0.1524)
				(type default)
			)
			(layer "F.SilkS")
		)
		(fp_line
			(start -0.7874 0.4064)
			(end -0.7874 -0.4064)
			(stroke
				(width 0.1524)
				(type default)
			)
			(layer "F.SilkS")
		)
		(fp_line
			(start 0.7874 -0.4064)
			(end 0.7874 0.4064)
			(stroke
				(width 0.1524)
				(type default)
			)
			(layer "F.SilkS")
		)
		(fp_line
			(start 0.7874 0.4064)
			(end -0.7874 0.4064)
			(stroke
				(width 0.1524)
				(type default)
			)
			(layer "F.SilkS")
		)
		(fp_line
			(start -0.67945 -0.305054)
			(end -0.12065 -0.305054)
			(stroke
				(width 0.1)
				(type default)
			)
			(layer "F.Fab")
		)
		(fp_line
			(start -0.67945 0.3048)
			(end -0.67945 -0.305054)
			(stroke
				(width 0.1)
				(type default)
			)
			(layer "F.Fab")
		)
		(fp_line
			(start -0.12065 -0.305054)
			(end -0.12065 -0.2794)
			(stroke
				(width 0.1)
				(type default)
			)
			(layer "F.Fab")
		)
		(fp_line
			(start -0.12065 -0.2794)
			(end 0.12065 -0.2794)
			(stroke
				(width 0.1)
				(type default)
			)
			(layer "F.Fab")
		)
		(fp_line
			(start -0.12065 0.2794)
			(end -0.12065 0.3048)
			(stroke
				(width 0.1)
				(type default)
			)
			(layer "F.Fab")
		)
		(fp_line
			(start -0.12065 0.3048)
			(end -0.67945 0.3048)
			(stroke
				(width 0.1)
				(type default)
			)
			(layer "F.Fab")
		)
		(fp_line
			(start 0.120396 0.2794)
			(end -0.12065 0.2794)
			(stroke
				(width 0.1)
				(type default)
			)
			(layer "F.Fab")
		)
		(fp_line
			(start 0.120396 0.3048)
			(end 0.120396 0.2794)
			(stroke
				(width 0.1)
				(type default)
			)
			(layer "F.Fab")
		)
		(fp_line
			(start 0.12065 -0.3048)
			(end 0.67945 -0.3048)
			(stroke
				(width 0.1)
				(type default)
			)
			(layer "F.Fab")
		)
		(fp_line
			(start 0.12065 -0.2794)
			(end 0.12065 -0.3048)
			(stroke
				(width 0.1)
				(type default)
			)
			(layer "F.Fab")
		)
		(fp_line
			(start 0.67945 -0.3048)
			(end 0.67945 0.3048)
			(stroke
				(width 0.1)
				(type default)
			)
			(layer "F.Fab")
		)
		(fp_line
			(start 0.67945 0.3048)
			(end 0.120396 0.3048)
			(stroke
				(width 0.1)
				(type default)
			)
			(layer "F.Fab")
		)
		(pad "1" smd circle
			(at -0.40005 0)
			(size 0 0)
			(layers "F.Cu" "F.Mask" "F.Paste")
			(net "SMB_INA230_3V3AUX_SCL_R")
		)
		(pad "2" smd circle
			(at 0.40005 0)
			(size 0 0)
			(layers "F.Cu" "F.Mask" "F.Paste")
			(net "SMB_INA230_3V3AUX_SCL")
		)
	)
)
